# T6G (Grand Teton) — schematic netlist excerpt (pin names and nets, part order shuffled) for the footprints in the layout excerpt that follows; sources: Cadence DE-HDL packaged netlist, KiCad conversion of 04192023_DAF0TMB3IC0_F0TG_MB_C_brd_V02_OCP.brd

R6104  Q_RES  0 5% CHIP  pkg 0402LF  page 174 : A = JTAG_CPU0_BYPASS ; B = JTAG_CPU0_BYPASS_R1
C629  Q_CAP  0.1UF 25V 10% X7R  pkg 0402  page 238 : A = P3V3_AUX ; B = GND

(kicad_pcb
	(version 20260206)
	(generator "pcbnew")
	(generator_version "10.0")
	(general
		(thickness 1.6)
		(legacy_teardrops no)
	)
	(paper "A4")
	(title_block
		(title "04192023_DAF0TMB3IC0_F0TG_MB_C_brd_V02_OCP.brd")
		(comment 1 "Grand Teton / footprints 4328-4329 of 8354")
	)
	(layers
		(0 "F.Cu" signal "TOP")
		(4 "In1.Cu" signal "GND")
		(6 "In2.Cu" signal "IN1")
		(8 "In3.Cu" signal "GND1")
		(10 "In4.Cu" signal "IN2")
		(12 "In5.Cu" signal "GND2")
		(14 "In6.Cu" signal "IN3")
		(16 "In7.Cu" signal "GND3")
		(18 "In8.Cu" signal "VCC")
		(20 "In9.Cu" signal "VCC1")
		(22 "In10.Cu" signal "GND4")
		(24 "In11.Cu" signal "IN4")
		(26 "In12.Cu" signal "GND5")
		(28 "In13.Cu" signal "IN5")
		(30 "In14.Cu" signal "GND6")
		(32 "In15.Cu" signal "IN6")
		(34 "In16.Cu" signal "GND7")
		(2 "B.Cu" signal "BOTTOM")
		(9 "F.Adhes" user "F.Adhesive")
		(11 "B.Adhes" user "B.Adhesive")
		(13 "F.Paste" user "Package Geometry/Pastemask Top")
		(15 "B.Paste" user "Package Geometry/Pastemask Bottom")
		(5 "F.SilkS" user "Ref Des/Silkscreen Top")
		(7 "B.SilkS" user "Ref Des/Silkscreen Bottom")
		(1 "F.Mask" user "Board Geometry/Soldermask Top")
		(3 "B.Mask" user "Board Geometry/Soldermask Bottom")
		(17 "Dwgs.User" user "User.Drawings")
		(19 "Cmts.User" user "User.Comments")
		(21 "Eco1.User" user "User.Eco1")
		(23 "Eco2.User" user "User.Eco2")
		(25 "Edge.Cuts" user "Board Geometry/Outline")
		(27 "Margin" user)
		(31 "F.CrtYd" user "Package Geometry/Place Bound Top")
		(29 "B.CrtYd" user "Package Geometry/Place Bound Bottom")
		(35 "F.Fab" user "Ref Des/Assembly Top")
		(33 "B.Fab" user "Ref Des/Assembly Bottom")
	)
	(footprint ""
		(layer "F.Cu")
		(at 229.560374 -154.15641)
		(property "Reference" "R6104"
			(at 0 0 0)
			(layer "F.SilkS")
			(hide yes)
			(effects
				(font
					(size 1.27 1.27)
				)
			)
		)
		(property "Value" ""
			(at 0 0 0)
			(layer "F.Fab")
			(effects
				(font
					(size 1.27 1.27)
				)
			)
		)
		(duplicate_pad_numbers_are_jumpers no)
		(fp_line
			(start -0.7874 -0.4064)
			(end 0.7874 -0.4064)
			(stroke
				(width 0.1524)
				(type default)
			)
			(layer "F.SilkS")
		)
		(fp_line
			(start -0.7874 0.4064)
			(end -0.7874 -0.4064)
			(stroke
				(width 0.1524)
				(type default)
			)
			(layer "F.SilkS")
		)
		(fp_line
			(start 0.7874 -0.4064)
			(end 0.7874 0.4064)
			(stroke
				(width 0.1524)
				(type default)
			)
			(layer "F.SilkS")
		)
		(fp_line
			(start 0.7874 0.4064)
			(end -0.7874 0.4064)
			(stroke
				(width 0.1524)
				(type default)
			)
			(layer "F.SilkS")
		)
		(fp_line
			(start -0.67945 -0.305054)
			(end -0.12065 -0.305054)
			(stroke
				(width 0.1)
				(type default)
			)
			(layer "F.Fab")
		)
		(fp_line
			(start -0.67945 0.3048)
			(end -0.67945 -0.305054)
			(stroke
				(width 0.1)
				(type default)
			)
			(layer "F.Fab")
		)
		(fp_line
			(start -0.12065 -0.305054)
			(end -0.12065 -0.2794)
			(stroke
				(width 0.1)
				(type default)
			)
			(layer "F.Fab")
		)
		(fp_line
			(start -0.12065 -0.2794)
			(end 0.12065 -0.2794)
			(stroke
				(width 0.1)
				(type default)
			)
			(layer "F.Fab")
		)
		(fp_line
			(start -0.12065 0.2794)
			(end -0.12065 0.3048)
			(stroke
				(width 0.1)
				(type default)
			)
			(layer "F.Fab")
		)
		(fp_line
			(start -0.12065 0.3048)
			(end -0.67945 0.3048)
			(stroke
				(width 0.1)
				(type default)
			)
			(layer "F.Fab")
		)
		(fp_line
			(start 0.120396 0.2794)
			(end -0.12065 0.2794)
			(stroke
				(width 0.1)
				(type default)
			)
			(layer "F.Fab")
		)
		(fp_line
			(start 0.120396 0.3048)
			(end 0.120396 0.2794)
			(stroke
				(width 0.1)
				(type default)
			)
			(layer "F.Fab")
		)
		(fp_line
			(start 0.12065 -0.3048)
			(end 0.67945 -0.3048)
			(stroke
				(width 0.1)
				(type default)
			)
			(layer "F.Fab")
		)
		(fp_line
			(start 0.12065 -0.2794)
			(end 0.12065 -0.3048)
			(stroke
				(width 0.1)
				(type default)
			)
			(layer "F.Fab")
		)
		(fp_line
			(start 0.67945 -0.3048)
			(end 0.67945 0.3048)
			(stroke
				(width 0.1)
				(type default)
			)
			(layer "F.Fab")
		)
		(fp_line
			(start 0.67945 0.3048)
			(end 0.120396 0.3048)
			(stroke
				(width 0.1)
				(type default)
			)
			(layer "F.Fab")
		)
		(pad "1" smd circle
			(at -0.40005 0)
			(size 0 0)
			(layers "F.Cu" "F.Mask" "F.Paste")
			(net "JTAG_CPU0_BYPASS")
		)
		(pad "2" smd circle
			(at 0.40005 0)
			(size 0 0)
			(layers "F.Cu" "F.Mask" "F.Paste")
			(net "JTAG_CPU0_BYPASS_R1")
		)
	)
	(footprint ""
		(layer "F.Cu")
		(at 316.821058 -118.910608)
		(property "Reference" "C629"
			(at 0 0 0)
			(layer "F.SilkS")
			(hide yes)
			(effects
				(font
					(size 1.27 1.27)
				)
			)
		)
		(property "Value" ""
			(at 0 0 0)
			(layer "F.Fab")
			(effects
				(font
					(size 1.27 1.27)
				)
			)
		)
		(duplicate_pad_numbers_are_jumpers no)
		(fp_line
			(start -0.7874 -0.4064)
			(end 0.7874 -0.4064)
			(stroke
				(width 0.1524)
				(type default)
			)
			(layer "F.SilkS")
		)
		(fp_line
			(start -0.7874 0.4064)
			(end -0.7874 -0.4064)
			(stroke
				(width 0.1524)
				(type default)
			)
			(layer "F.SilkS")
		)
		(fp_line
			(start 0.7874 -0.4064)
			(end 0.7874 0.4064)
			(stroke
				(width 0.1524)
				(type default)
			)
			(layer "F.SilkS")
		)
		(fp_line
			(start 0.7874 0.4064)
			(end -0.7874 0.4064)
			(stroke
				(width 0.1524)
				(type default)
			)
			(layer "F.SilkS")
		)
		(fp_line
			(start -0.67945 -0.305054)
			(end -0.12065 -0.305054)
			(stroke
				(width 0.1)
				(type default)
			)
			(layer "F.Fab")
		)
		(fp_line
			(start -0.67945 0.3048)
			(end -0.67945 -0.305054)
			(stroke
				(width 0.1)
				(type default)
			)
			(layer "F.Fab")
		)
		(fp_line
			(start -0.12065 -0.305054)
			(end -0.12065 -0.2794)
			(stroke
				(width 0.1)
				(type default)
			)
			(layer "F.Fab")
		)
		(fp_line
			(start -0.12065 -0.2794)
			(end 0.12065 -0.2794)
			(stroke
				(width 0.1)
				(type default)
			)
			(layer "F.Fab")
		)
		(fp_line
			(start -0.12065 0.2794)
			(end -0.12065 0.3048)
			(stroke
				(width 0.1)
				(type default)
			)
			(layer "F.Fab")
		)
		(fp_line
			(start -0.12065 0.3048)
			(end -0.67945 0.3048)
			(stroke
				(width 0.1)
				(type default)
			)
			(layer "F.Fab")
		)
		(fp_line
			(start 0.120396 0.2794)
			(end -0.12065 0.2794)
			(stroke
				(width 0.1)
				(type default)
			)
			(layer "F.Fab")
		)
		(fp_line
			(start 0.120396 0.3048)
			(end 0.120396 0.2794)
			(stroke
				(width 0.1)
				(type default)
			)
			(layer "F.Fab")
		)
		(fp_line
			(start 0.12065 -0.3048)
			(end 0.67945 -0.3048)
			(stroke
				(width 0.1)
				(type default)
			)
			(layer "F.Fab")
		)
		(fp_line
			(start 0.12065 -0.2794)
			(end 0.12065 -0.3048)
			(stroke
				(width 0.1)
				(type default)
			)
			(layer "F.Fab")
		)
		(fp_line
			(start 0.67945 -0.3048)
			(end 0.67945 0.3048)
			(stroke
				(width 0.1)
				(type default)
			)
			(layer "F.Fab")
		)
		(fp_line
			(start 0.67945 0.3048)
			(end 0.120396 0.3048)
			(stroke
				(width 0.1)
				(type default)
			)
			(layer "F.Fab")
		)
		(pad "1" smd circle
			(at -0.40005 0)
			(size 0 0)
			(layers "F.Cu" "F.Mask" "F.Paste")
			(net "P3V3_AUX")
		)
		(pad "2" smd circle
			(at 0.40005 0)
			(size 0 0)
			(layers "F.Cu" "F.Mask" "F.Paste")
			(net "GND")
		)
	)
)
